(kicad_pcb
	(version 20260206)
	(generator "pcbnew")
	(generator_version "10.0")
	(general
		(thickness 1.6)
		(legacy_teardrops no)
	)
	(paper "A4")
	(title_block
		(title "Bryce Canyon_IOM_IOC_16318-2_OCP.brd")
		(comment 1 "Bryce Canyon / footprints 293-299 of 1605")
	)
	(layers
		(0 "F.Cu" signal "TOP")
		(4 "In1.Cu" signal "L2GND")
		(6 "In2.Cu" signal "L3")
		(8 "In3.Cu" signal "L4VCC")
		(10 "In4.Cu" signal "L5VCC")
		(12 "In5.Cu" signal "L6")
		(14 "In6.Cu" signal "L7GND")
		(2 "B.Cu" signal "BOTTOM")
		(9 "F.Adhes" user "F.Adhesive")
		(11 "B.Adhes" user "B.Adhesive")
		(13 "F.Paste" user "Package Geometry/Pastemask Top")
		(15 "B.Paste" user "Package Geometry/Pastemask Bottom")
		(5 "F.SilkS" user "Ref Des/Silkscreen Top")
		(7 "B.SilkS" user "Ref Des/Silkscreen Bottom")
		(1 "F.Mask" user "Board Geometry/Soldermask Top")
		(3 "B.Mask" user "Board Geometry/Soldermask Bottom")
		(17 "Dwgs.User" user "User.Drawings")
		(19 "Cmts.User" user "User.Comments")
		(21 "Eco1.User" user "User.Eco1")
		(23 "Eco2.User" user "User.Eco2")
		(25 "Edge.Cuts" user "Board Geometry/Outline")
		(27 "Margin" user)
		(31 "F.CrtYd" user "Package Geometry/Place Bound Top")
		(29 "B.CrtYd" user "Package Geometry/Place Bound Bottom")
		(35 "F.Fab" user "Ref Des/Assembly Top")
		(33 "B.Fab" user "Ref Des/Assembly Bottom")
	)
	(footprint ""
		(layer "F.Cu")
		(at 206.004414 -13.526008 90)
		(property "Reference" "Q28"
			(at 0 0 90)
			(layer "F.SilkS")
			(hide yes)
			(effects
				(font
					(size 1.27 1.27)
				)
			)
		)
		(property "Value" "SSM6P39TU-GP"
			(at 0.0508 -11.5824 90)
			(unlocked yes)
			(layer "F.Fab")
			(hide yes)
			(effects
				(font
					(size 1.016 1.016)
					(thickness 0.1524)
				)
			)
		)
		(property "Device Type" "UMT6H30"
			(at 0.0508 -13.1572 90)
			(unlocked yes)
			(layer "F.Fab")
			(hide yes)
			(effects
				(font
					(size 1.016 1.016)
					(thickness 0.1524)
				)
			)
		)
		(duplicate_pad_numbers_are_jumpers no)
		(fp_line
			(start 1.524 -0.36449)
			(end 1.524 -1.82245)
			(stroke
				(width 0.508)
				(type default)
			)
			(layer "F.SilkS")
		)
		(fp_line
			(start 1.524 -0.36449)
			(end 1.45796 -0.36449)
			(stroke
				(width 0.1524)
				(type default)
			)
			(layer "F.SilkS")
		)
		(fp_line
			(start 1.524 -0.36449)
			(end 1.524 0.36449)
			(stroke
				(width 0.1524)
				(type default)
			)
			(layer "F.SilkS")
		)
		(fp_line
			(start 1.45796 -0.36449)
			(end 1.09347 0)
			(stroke
				(width 0.1524)
				(type default)
			)
			(layer "F.SilkS")
		)
		(fp_line
			(start -1.27 -0.36449)
			(end 1.524 -0.36449)
			(stroke
				(width 0.1524)
				(type default)
			)
			(layer "F.SilkS")
		)
		(fp_line
			(start -1.27 -0.36449)
			(end -1.27 0.36449)
			(stroke
				(width 0.1524)
				(type default)
			)
			(layer "F.SilkS")
		)
		(fp_line
			(start 1.09347 0)
			(end 1.45796 0.36449)
			(stroke
				(width 0.1524)
				(type default)
			)
			(layer "F.SilkS")
		)
		(fp_line
			(start 1.524 0.36449)
			(end -1.27 0.36449)
			(stroke
				(width 0.1524)
				(type default)
			)
			(layer "F.SilkS")
		)
		(fp_poly
			(pts
				(xy -0.65024 0.36449) (xy -0.65024 -0.36449) (xy 0.65024 -0.36449) (xy 0.65024 0.36449)
			)
			(stroke
				(width 0)
				(type default)
			)
			(fill yes)
			(layer "F.SilkS")
		)
		(fp_poly
			(pts
				(xy 1.016 -1.0668) (xy 1.016 1.0668) (xy -1.016 1.0668) (xy -1.016 -1.0668)
			)
			(stroke
				(width 0)
				(type default)
			)
			(fill no)
			(layer "F.CrtYd")
		)
		(fp_poly
			(pts
				(xy -1.524 1.905) (xy 1.524 1.905) (xy 1.524 -1.06426) (xy 1.016 -1.06426) (xy 1.016 1.0668) (xy -1.016 1.0668)
				(xy -1.016 -1.0668) (xy 1.524 -1.0668) (xy 1.524 -1.905) (xy -1.524 -1.905)
			)
			(stroke
				(width 0)
				(type default)
			)
			(fill no)
			(layer "F.CrtYd")
		)
		(fp_poly
			(pts
				(xy -1.524 -1.905) (xy -1.524 1.905) (xy 1.524 1.905) (xy 1.524 -1.905)
			)
			(stroke
				(width 0)
				(type default)
			)
			(fill no)
			(layer "F.Fab")
		)
		(pad "1" smd rect
			(at 0.65024 -1.02489 90)
			(size 0.4064 0.8128)
			(layers "F.Cu" "F.Mask" "F.Paste")
			(net "P3V3_STBY")
		)
		(pad "2" smd rect
			(at 0 -1.02489 90)
			(size 0.4064 0.8128)
			(layers "F.Cu" "F.Mask" "F.Paste")
			(net "BMC_ML_PWR_YELLOW_LED_R")
		)
		(pad "3" smd rect
			(at -0.65024 -1.02489 90)
			(size 0.4064 0.8128)
			(layers "F.Cu" "F.Mask" "F.Paste")
			(net "ML_PWR_BLUE_LED")
		)
		(pad "4" smd rect
			(at -0.65024 1.02489 90)
			(size 0.4064 0.8128)
			(layers "F.Cu" "F.Mask" "F.Paste")
			(net "P5V_STBY")
		)
		(pad "5" smd rect
			(at 0 1.02489 90)
			(size 0.4064 0.8128)
			(layers "F.Cu" "F.Mask" "F.Paste")
			(net "BMC_ML_PWR_BLUE_LED_L")
		)
		(pad "6" smd rect
			(at 0.65024 1.02489 90)
			(size 0.4064 0.8128)
			(layers "F.Cu" "F.Mask" "F.Paste")
			(net "ML_PWR_YELLOW_LED")
		)
	)
	(footprint ""
		(layer "F.Cu")
		(at 157.3276 -143.637 180)
		(property "Reference" "R521"
			(at 0 0 180)
			(layer "F.SilkS")
			(hide yes)
			(effects
				(font
					(size 1.27 1.27)
				)
			)
		)
		(property "Value" "15KR2F-GP"
			(at 0.064008 -3.993896 180)
			(unlocked yes)
			(layer "F.Fab")
			(hide yes)
			(effects
				(font
					(size 1.016 1.016)
					(thickness 0.1524)
				)
			)
		)
		(property "Device Type" "R402H16"
			(at 0.064008 -5.517896 180)
			(unlocked yes)
			(layer "F.Fab")
			(hide yes)
			(effects
				(font
					(size 1.016 1.016)
					(thickness 0.1524)
				)
			)
		)
		(duplicate_pad_numbers_are_jumpers no)
		(fp_line
			(start 0.508 -0.9398)
			(end -0.508 -0.9398)
			(stroke
				(width 0.1524)
				(type default)
			)
			(layer "F.SilkS")
		)
		(fp_line
			(start -0.508 -0.9398)
			(end -0.508 0.9398)
			(stroke
				(width 0.1524)
				(type default)
			)
			(layer "F.SilkS")
		)
		(fp_rect
			(start -0.508 0.9398)
			(end 0.508 -0.9398)
			(stroke
				(width 0)
				(type default)
			)
			(fill no)
			(layer "F.CrtYd")
		)
		(fp_rect
			(start -0.508 0.9398)
			(end 0.508 -0.9398)
			(stroke
				(width 0)
				(type default)
			)
			(fill no)
			(layer "F.Fab")
		)
		(pad "1" smd custom
			(at 0 -0.4445 180)
			(size 0.1397 0.1397)
			(layers "F.Cu" "F.Mask" "F.Paste")
			(net "PWRGD_P1V8_STBY")
			(options
				(clearance outline)
				(anchor circle)
			)
			(primitives
				(gr_poly
					(pts
						(arc
							(start -0.1778 -0.2794)
							(mid -0.249642 -0.249642)
							(end -0.2794 -0.1778)
						)
						(arc
							(start -0.2794 0.1778)
							(mid -0.249642 0.249642)
							(end -0.1778 0.2794)
						)
						(arc
							(start 0.1778 0.2794)
							(mid 0.249642 0.249642)
							(end 0.2794 0.1778)
						)
						(arc
							(start 0.2794 -0.1778)
							(mid 0.249642 -0.249642)
							(end 0.1778 -0.2794)
						)
					)
					(width 0)
					(fill yes)
				)
			)
		)
		(pad "2" smd custom
			(at 0 0.4445 180)
			(size 0.1397 0.1397)
			(layers "F.Cu" "F.Mask" "F.Paste")
			(net "GND")
			(options
				(clearance outline)
				(anchor circle)
			)
			(primitives
				(gr_poly
					(pts
						(arc
							(start -0.1778 -0.2794)
							(mid -0.249642 -0.249642)
							(end -0.2794 -0.1778)
						)
						(arc
							(start -0.2794 0.1778)
							(mid -0.249642 0.249642)
							(end -0.1778 0.2794)
						)
						(arc
							(start 0.1778 0.2794)
							(mid 0.249642 0.249642)
							(end 0.2794 0.1778)
						)
						(arc
							(start 0.2794 -0.1778)
							(mid 0.249642 -0.249642)
							(end 0.1778 -0.2794)
						)
					)
					(width 0)
					(fill yes)
				)
			)
		)
	)
	(footprint ""
		(layer "F.Cu")
		(at 98.29038 -177.08372 90)
		(property "Reference" "C141"
			(at 0 0 90)
			(layer "F.SilkS")
			(hide yes)
			(effects
				(font
					(size 1.27 1.27)
				)
			)
		)
		(property "Value" "SCD1U16V2KX-3GP"
			(at 1.1811 -2.7051 90)
			(unlocked yes)
			(layer "F.Fab")
			(hide yes)
			(effects
				(font
					(size 1.016 1.016)
					(thickness 0.1524)
				)
			)
		)
		(property "Device Type" "C402H22"
			(at 1.1811 -4.2291 90)
			(unlocked yes)
			(layer "F.Fab")
			(hide yes)
			(effects
				(font
					(size 1.016 1.016)
					(thickness 0.1524)
				)
			)
		)
		(duplicate_pad_numbers_are_jumpers no)
		(fp_rect
			(start -0.4318 0.9525)
			(end 0.4318 -0.9525)
			(stroke
				(width 0)
				(type default)
			)
			(fill no)
			(layer "F.CrtYd")
		)
		(fp_rect
			(start -0.4318 0.9525)
			(end 0.4318 -0.9525)
			(stroke
				(width 0)
				(type default)
			)
			(fill no)
			(layer "F.Fab")
		)
		(pad "1" smd custom
			(at 0 -0.4445 90)
			(size 0.1524 0.1524)
			(layers "F.Cu" "F.Mask" "F.Paste")
			(net "P3V3_STBY")
			(options
				(clearance outline)
				(anchor circle)
			)
			(primitives
				(gr_poly
					(pts
						(arc
							(start 0.3048 -0.2032)
							(mid 0.275042 -0.275042)
							(end 0.2032 -0.3048)
						)
						(arc
							(start -0.2032 -0.3048)
							(mid -0.275042 -0.275042)
							(end -0.3048 -0.2032)
						)
						(arc
							(start -0.3048 0.2032)
							(mid -0.275042 0.275042)
							(end -0.2032 0.3048)
						)
						(arc
							(start 0.2032 0.3048)
							(mid 0.275042 0.275042)
							(end 0.3048 0.2032)
						)
					)
					(width 0)
					(fill yes)
				)
			)
		)
		(pad "2" smd custom
			(at 0 0.4445 90)
			(size 0.1524 0.1524)
			(layers "F.Cu" "F.Mask" "F.Paste")
			(net "GND")
			(options
				(clearance outline)
				(anchor circle)
			)
			(primitives
				(gr_poly
					(pts
						(arc
							(start 0.3048 -0.2032)
							(mid 0.275042 -0.275042)
							(end 0.2032 -0.3048)
						)
						(arc
							(start -0.2032 -0.3048)
							(mid -0.275042 -0.275042)
							(end -0.3048 -0.2032)
						)
						(arc
							(start -0.3048 0.2032)
							(mid -0.275042 0.275042)
							(end -0.2032 0.3048)
						)
						(arc
							(start 0.2032 0.3048)
							(mid 0.275042 0.275042)
							(end 0.3048 0.2032)
						)
					)
					(width 0)
					(fill yes)
				)
			)
		)
	)
	(footprint ""
		(layer "F.Cu")
		(at 49.948592 -166.451534)
		(property "Reference" "R778"
			(at 0 0 0)
			(layer "F.SilkS")
			(hide yes)
			(effects
				(font
					(size 1.27 1.27)
				)
			)
		)
		(property "Value" "866R2F-GP"
			(at 0.064008 -3.993896 0)
			(unlocked yes)
			(layer "F.Fab")
			(hide yes)
			(effects
				(font
					(size 1.016 1.016)
					(thickness 0.1524)
				)
			)
		)
		(property "Device Type" "R402H16"
			(at 0.064008 -5.517896 0)
			(unlocked yes)
			(layer "F.Fab")
			(hide yes)
			(effects
				(font
					(size 1.016 1.016)
					(thickness 0.1524)
				)
			)
		)
		(duplicate_pad_numbers_are_jumpers no)
		(fp_line
			(start -0.508 -0.9398)
			(end -0.508 0.9398)
			(stroke
				(width 0.1524)
				(type default)
			)
			(layer "F.SilkS")
		)
		(fp_line
			(start 0.508 -0.9398)
			(end -0.508 -0.9398)
			(stroke
				(width 0.1524)
				(type default)
			)
			(layer "F.SilkS")
		)
		(fp_rect
			(start -0.508 0.9398)
			(end 0.508 -0.9398)
			(stroke
				(width 0)
				(type default)
			)
			(fill no)
			(layer "F.CrtYd")
		)
		(fp_rect
			(start -0.508 0.9398)
			(end 0.508 -0.9398)
			(stroke
				(width 0)
				(type default)
			)
			(fill no)
			(layer "F.Fab")
		)
		(pad "1" smd custom
			(at 0 -0.4445)
			(size 0.1397 0.1397)
			(layers "F.Cu" "F.Mask" "F.Paste")
			(net "P2V5_STBY")
			(options
				(clearance outline)
				(anchor circle)
			)
			(primitives
				(gr_poly
					(pts
						(arc
							(start -0.1778 -0.2794)
							(mid -0.249642 -0.249642)
							(end -0.2794 -0.1778)
						)
						(arc
							(start -0.2794 0.1778)
							(mid -0.249642 0.249642)
							(end -0.1778 0.2794)
						)
						(arc
							(start 0.1778 0.2794)
							(mid 0.249642 0.249642)
							(end 0.2794 0.1778)
						)
						(arc
							(start 0.2794 -0.1778)
							(mid 0.249642 -0.249642)
							(end 0.1778 -0.2794)
						)
					)
					(width 0)
					(fill yes)
				)
			)
		)
		(pad "2" smd custom
			(at 0 0.4445)
			(size 0.1397 0.1397)
			(layers "F.Cu" "F.Mask" "F.Paste")
			(net "ADC_P2V5_STBY")
			(options
				(clearance outline)
				(anchor circle)
			)
			(primitives
				(gr_poly
					(pts
						(arc
							(start -0.1778 -0.2794)
							(mid -0.249642 -0.249642)
							(end -0.2794 -0.1778)
						)
						(arc
							(start -0.2794 0.1778)
							(mid -0.249642 0.249642)
							(end -0.1778 0.2794)
						)
						(arc
							(start 0.1778 0.2794)
							(mid 0.249642 0.249642)
							(end 0.2794 0.1778)
						)
						(arc
							(start 0.2794 -0.1778)
							(mid 0.249642 -0.249642)
							(end 0.1778 -0.2794)
						)
					)
					(width 0)
					(fill yes)
				)
			)
		)
	)
	(footprint ""
		(layer "F.Cu")
		(at 199.75068 -12.779248 180)
		(property "Reference" "U47"
			(at 0 0 180)
			(layer "F.SilkS")
			(hide yes)
			(effects
				(font
					(size 1.27 1.27)
				)
			)
		)
		(property "Value" "74LVC1G86DCKR-GP"
			(at -2.3368 -8.6868 180)
			(unlocked yes)
			(layer "F.Fab")
			(hide yes)
			(effects
				(font
					(size 1.016 1.016)
					(thickness 0.1524)
				)
			)
		)
		(property "Device Type" "SC70-5H44"
			(at -2.3114 -10.414 180)
			(unlocked yes)
			(layer "F.Fab")
			(hide yes)
			(effects
				(font
					(size 1.016 1.016)
					(thickness 0.1524)
				)
			)
		)
		(duplicate_pad_numbers_are_jumpers no)
		(fp_line
			(start 1.3843 -1.8034)
			(end 1.3843 -1.1176)
			(stroke
				(width 0.3302)
				(type default)
			)
			(layer "F.SilkS")
		)
		(fp_line
			(start 1.27 1.7018)
			(end -1.27 1.7018)
			(stroke
				(width 0.1524)
				(type default)
			)
			(layer "F.SilkS")
		)
		(fp_line
			(start 1.27 -1.7018)
			(end 1.27 1.7018)
			(stroke
				(width 0.1524)
				(type default)
			)
			(layer "F.SilkS")
		)
		(fp_line
			(start 0.6604 -1.8034)
			(end 1.3843 -1.8034)
			(stroke
				(width 0.3302)
				(type default)
			)
			(layer "F.SilkS")
		)
		(fp_line
			(start -1.27 1.7018)
			(end -1.27 -1.7018)
			(stroke
				(width 0.1524)
				(type default)
			)
			(layer "F.SilkS")
		)
		(fp_line
			(start -1.27 -1.7018)
			(end 1.27 -1.7018)
			(stroke
				(width 0.1524)
				(type default)
			)
			(layer "F.SilkS")
		)
		(fp_rect
			(start -1.524 1.9558)
			(end 1.524 -1.9558)
			(stroke
				(width 0)
				(type default)
			)
			(fill no)
			(layer "F.CrtYd")
		)
		(fp_poly
			(pts
				(xy -1.524 -1.9558) (xy 1.524 -1.9558) (xy 1.524 1.9558) (xy -1.524 1.9558)
			)
			(stroke
				(width 0)
				(type default)
			)
			(fill no)
			(layer "F.Fab")
		)
		(pad "1" smd rect
			(at 0.65024 -0.8255 180)
			(size 0.4064 1.2192)
			(layers "F.Cu" "F.Mask" "F.Paste")
			(net "IOC_EXT1_LED_B")
		)
		(pad "2" smd rect
			(at 0 -0.8255 180)
			(size 0.4064 1.2192)
			(layers "F.Cu" "F.Mask" "F.Paste")
			(net "IOC_EXT1_LED_Y")
		)
		(pad "3" smd rect
			(at -0.65024 -0.8255 180)
			(size 0.4064 1.2192)
			(layers "F.Cu" "F.Mask" "F.Paste")
			(net "GND")
		)
		(pad "4" smd rect
			(at -0.65024 0.8255 180)
			(size 0.4064 1.2192)
			(layers "F.Cu" "F.Mask" "F.Paste")
			(net "IOC_EXT1_LED_Y_XOR")
		)
		(pad "5" smd rect
			(at 0.65024 0.8255 180)
			(size 0.4064 1.2192)
			(layers "F.Cu" "F.Mask" "F.Paste")
			(net "P1V8")
		)
	)
	(footprint ""
		(layer "F.Cu")
		(at 70.59803 -139.546076 90)
		(property "Reference" "U5"
			(at 0 0 90)
			(layer "F.SilkS")
			(hide yes)
			(effects
				(font
					(size 1.27 1.27)
				)
			)
		)
		(property "Value" "74LVC2G07GW-GP"
			(at -2.3622 -8.2042 90)
			(unlocked yes)
			(layer "F.Fab")
			(hide yes)
			(effects
				(font
					(size 1.016 1.016)
					(thickness 0.1524)
				)
			)
		)
		(property "Device Type" "SOT-363H44"
			(at -2.3622 -10.1092 90)
			(unlocked yes)
			(layer "F.Fab")
			(hide yes)
			(effects
				(font
					(size 1.016 1.016)
					(thickness 0.1524)
				)
			)
		)
		(duplicate_pad_numbers_are_jumpers no)
		(fp_line
			(start 1.4478 -1.7018)
			(end -1.4478 -1.7018)
			(stroke
				(width 0.1524)
				(type default)
			)
			(layer "F.SilkS")
		)
		(fp_line
			(start -1.4478 -1.7018)
			(end -1.4478 1.7018)
			(stroke
				(width 0.1524)
				(type default)
			)
			(layer "F.SilkS")
		)
		(fp_line
			(start -1.27 1.524)
			(end -1.27 0.6604)
			(stroke
				(width 0.4826)
				(type default)
			)
			(layer "F.SilkS")
		)
		(fp_line
			(start 1.4478 1.7018)
			(end 1.4478 -1.7018)
			(stroke
				(width 0.1524)
				(type default)
			)
			(layer "F.SilkS")
		)
		(fp_line
			(start -1.4478 1.7018)
			(end 1.4478 1.7018)
			(stroke
				(width 0.1524)
				(type default)
			)
			(layer "F.SilkS")
		)
		(fp_poly
			(pts
				(xy -1.524 -1.778) (xy 1.524 -1.778) (xy 1.524 1.778) (xy -1.524 1.778)
			)
			(stroke
				(width 0)
				(type default)
			)
			(fill no)
			(layer "F.CrtYd")
		)
		(fp_poly
			(pts
				(xy -1.524 -1.778) (xy 1.524 -1.778) (xy 1.524 1.778) (xy -1.524 1.778)
			)
			(stroke
				(width 0)
				(type default)
			)
			(fill no)
			(layer "F.Fab")
		)
		(pad "1" smd rect
			(at -0.65024 0.9398 90)
			(size 0.4064 1.016)
			(layers "F.Cu" "F.Mask" "F.Paste")
			(net "FP_PWR_BTN_N_R")
		)
		(pad "2" smd rect
			(at 0 0.9398 90)
			(size 0.4064 1.016)
			(layers "F.Cu" "F.Mask" "F.Paste")
			(net "GND")
		)
		(pad "3" smd rect
			(at 0.65024 0.9398 90)
			(size 0.4064 1.016)
			(layers "F.Cu" "F.Mask" "F.Paste")
			(net "FP_RESET_RC_N")
		)
		(pad "4" smd rect
			(at 0.65024 -0.9398 90)
			(size 0.4064 1.016)
			(layers "F.Cu" "F.Mask" "F.Paste")
			(net "FP_RETBTN")
		)
		(pad "5" smd rect
			(at 0 -0.9398 90)
			(size 0.4064 1.016)
			(layers "F.Cu" "F.Mask" "F.Paste")
			(net "P3V3_STBY")
		)
		(pad "6" smd rect
			(at -0.65024 -0.9398 90)
			(size 0.4064 1.016)
			(layers "F.Cu" "F.Mask" "F.Paste")
			(net "FP_PWRBTN")
		)
	)
	(footprint ""
		(layer "F.Cu")
		(at 55.7784 -181.3306)
		(property "Reference" "C172"
			(at 0 0 0)
			(layer "F.SilkS")
			(hide yes)
			(effects
				(font
					(size 1.27 1.27)
				)
			)
		)
		(property "Value" "SC10U6D3V5KX-4GP"
			(at -0.0762 -6.1214 0)
			(unlocked yes)
			(layer "F.Fab")
			(hide yes)
			(effects
				(font
					(size 1.016 1.016)
					(thickness 0.1524)
				)
			)
		)
		(property "Device Type" "C805H58"
			(at -0.0762 -8.1534 0)
			(unlocked yes)
			(layer "F.Fab")
			(hide yes)
			(effects
				(font
					(size 1.016 1.016)
					(thickness 0.1524)
				)
			)
		)
		(duplicate_pad_numbers_are_jumpers no)
		(fp_line
			(start 0.635 0)
			(end -0.635 0)
			(stroke
				(width 0.508)
				(type default)
			)
			(layer "F.SilkS")
		)
		(fp_rect
			(start -0.9652 1.778)
			(end 0.9652 -1.778)
			(stroke
				(width 0)
				(type default)
			)
			(fill no)
			(layer "F.CrtYd")
		)
		(fp_poly
			(pts
				(xy -0.9652 -1.778) (xy 0.9652 -1.778) (xy 0.9652 1.778) (xy -0.9652 1.778)
			)
			(stroke
				(width 0)
				(type default)
			)
			(fill no)
			(layer "F.Fab")
		)
		(pad "1" smd rect
			(at 0 -0.9652)
			(size 1.397 1.143)
			(layers "F.Cu" "F.Mask" "F.Paste")
			(net "P3V3_STBY_OUT")
		)
		(pad "2" smd rect
			(at 0 0.9652)
			(size 1.397 1.143)
			(layers "F.Cu" "F.Mask" "F.Paste")
			(net "GND")
		)
	)
)
